(kicad_pcb
	(version 20260206)
	(generator "pcbnew")
	(generator_version "10.0")
	(general
		(thickness 1.6)
		(legacy_teardrops no)
	)
	(paper "A4")
	(title_block
		(title "Bryce Canyon_IOM_M2_16342-2_OCP.brd")
		(comment 1 "Bryce Canyon / footprints 378-383 of 1146")
	)
	(layers
		(0 "F.Cu" signal "TOP")
		(4 "In1.Cu" signal "L2GND")
		(6 "In2.Cu" signal "L3")
		(8 "In3.Cu" signal "L4VCC")
		(10 "In4.Cu" signal "L5VCC")
		(12 "In5.Cu" signal "L6")
		(14 "In6.Cu" signal "L7GND")
		(2 "B.Cu" signal "BOTTOM")
		(9 "F.Adhes" user "F.Adhesive")
		(11 "B.Adhes" user "B.Adhesive")
		(13 "F.Paste" user "Package Geometry/Pastemask Top")
		(15 "B.Paste" user "Package Geometry/Pastemask Bottom")
		(5 "F.SilkS" user "Ref Des/Silkscreen Top")
		(7 "B.SilkS" user "Ref Des/Silkscreen Bottom")
		(1 "F.Mask" user "Board Geometry/Soldermask Top")
		(3 "B.Mask" user "Board Geometry/Soldermask Bottom")
		(17 "Dwgs.User" user "User.Drawings")
		(19 "Cmts.User" user "User.Comments")
		(21 "Eco1.User" user "User.Eco1")
		(23 "Eco2.User" user "User.Eco2")
		(25 "Edge.Cuts" user "Board Geometry/Outline")
		(27 "Margin" user)
		(31 "F.CrtYd" user "Package Geometry/Place Bound Top")
		(29 "B.CrtYd" user "Package Geometry/Place Bound Bottom")
		(35 "F.Fab" user "Ref Des/Assembly Top")
		(33 "B.Fab" user "Ref Des/Assembly Bottom")
	)
	(footprint ""
		(layer "F.Cu")
		(at 162.902138 -15.292578 180)
		(property "Reference" "C211"
			(at 0 0 180)
			(layer "F.SilkS")
			(hide yes)
			(effects
				(font
					(size 1.27 1.27)
				)
			)
		)
		(property "Value" "SCD1U50V3KX-GP"
			(at 0 -2.8194 180)
			(unlocked yes)
			(layer "F.Fab")
			(hide yes)
			(effects
				(font
					(size 1.016 1.016)
					(thickness 0.1524)
				)
			)
		)
		(property "Device Type" "C603H36"
			(at 0 -4.3434 180)
			(unlocked yes)
			(layer "F.Fab")
			(hide yes)
			(effects
				(font
					(size 1.016 1.016)
					(thickness 0.1524)
				)
			)
		)
		(duplicate_pad_numbers_are_jumpers no)
		(fp_line
			(start 0.508 0)
			(end -0.508 0)
			(stroke
				(width 0.2032)
				(type default)
			)
			(layer "F.SilkS")
		)
		(fp_rect
			(start -0.5842 1.3335)
			(end 0.5842 -1.3335)
			(stroke
				(width 0)
				(type default)
			)
			(fill no)
			(layer "F.CrtYd")
		)
		(fp_rect
			(start -0.5842 1.3335)
			(end 0.5842 -1.3335)
			(stroke
				(width 0)
				(type default)
			)
			(fill no)
			(layer "F.Fab")
		)
		(pad "1" smd custom
			(at 0 -0.762 180)
			(size 0.2159 0.2159)
			(layers "F.Cu" "F.Mask" "F.Paste")
			(net "P1V8_STBY")
			(options
				(clearance outline)
				(anchor circle)
			)
			(primitives
				(gr_poly
					(pts
						(arc
							(start -0.3302 -0.4318)
							(mid -0.402042 -0.402042)
							(end -0.4318 -0.3302)
						)
						(arc
							(start -0.4318 0.3302)
							(mid -0.402042 0.402042)
							(end -0.3302 0.4318)
						)
						(arc
							(start 0.3302 0.4318)
							(mid 0.402042 0.402042)
							(end 0.4318 0.3302)
						)
						(arc
							(start 0.4318 -0.3302)
							(mid 0.402042 -0.402042)
							(end 0.3302 -0.4318)
						)
					)
					(width 0)
					(fill yes)
				)
			)
		)
		(pad "2" smd custom
			(at 0 0.762 180)
			(size 0.2159 0.2159)
			(layers "F.Cu" "F.Mask" "F.Paste")
			(net "P1V8_STBY_VFB_R")
			(options
				(clearance outline)
				(anchor circle)
			)
			(primitives
				(gr_poly
					(pts
						(arc
							(start -0.3302 -0.4318)
							(mid -0.402042 -0.402042)
							(end -0.4318 -0.3302)
						)
						(arc
							(start -0.4318 0.3302)
							(mid -0.402042 0.402042)
							(end -0.3302 0.4318)
						)
						(arc
							(start 0.3302 0.4318)
							(mid 0.402042 0.402042)
							(end 0.4318 0.3302)
						)
						(arc
							(start 0.4318 -0.3302)
							(mid 0.402042 -0.402042)
							(end 0.3302 -0.4318)
						)
					)
					(width 0)
					(fill yes)
				)
			)
		)
	)
	(footprint ""
		(layer "F.Cu")
		(at 78.796896 -143.754602 -90)
		(property "Reference" "U105"
			(at 0 0 270)
			(layer "F.SilkS")
			(hide yes)
			(effects
				(font
					(size 1.27 1.27)
				)
			)
		)
		(property "Value" "SN74CBTLV3245APWR-GP"
			(at -0.889 -6.2738 270)
			(unlocked yes)
			(layer "F.Fab")
			(hide yes)
			(effects
				(font
					(size 1.016 1.016)
					(thickness 0.1524)
				)
			)
		)
		(property "Device Type" "TSOIC20H48"
			(at -0.9144 -7.8994 270)
			(unlocked yes)
			(layer "F.Fab")
			(hide yes)
			(effects
				(font
					(size 1.016 1.016)
					(thickness 0.1524)
				)
			)
		)
		(duplicate_pad_numbers_are_jumpers no)
		(fp_line
			(start -3.556 4.064)
			(end -3.556 1.778)
			(stroke
				(width 0.508)
				(type default)
			)
			(layer "F.SilkS")
		)
		(fp_line
			(start -3.556 1.397)
			(end -3.556 1.778)
			(stroke
				(width 0.2032)
				(type default)
			)
			(layer "F.SilkS")
		)
		(fp_line
			(start 3.175 1.397)
			(end -3.556 1.397)
			(stroke
				(width 0.2032)
				(type default)
			)
			(layer "F.SilkS")
		)
		(fp_line
			(start -2.667 0)
			(end -3.556 0.889)
			(stroke
				(width 0.2032)
				(type default)
			)
			(layer "F.SilkS")
		)
		(fp_line
			(start -2.667 0)
			(end -3.556 -0.889)
			(stroke
				(width 0.2032)
				(type default)
			)
			(layer "F.SilkS")
		)
		(fp_line
			(start -3.556 -1.397)
			(end -3.556 4.064)
			(stroke
				(width 0.2032)
				(type default)
			)
			(layer "F.SilkS")
		)
		(fp_line
			(start -3.556 -1.397)
			(end 3.175 -1.397)
			(stroke
				(width 0.2032)
				(type default)
			)
			(layer "F.SilkS")
		)
		(fp_line
			(start 3.175 -1.397)
			(end 3.175 1.397)
			(stroke
				(width 0.2032)
				(type default)
			)
			(layer "F.SilkS")
		)
		(fp_poly
			(pts
				(xy -3.25628 -1.8542) (xy 3.25628 -1.8542) (xy 3.25628 1.8542) (xy -3.25628 1.8542)
			)
			(stroke
				(width 0)
				(type default)
			)
			(fill yes)
			(layer "F.SilkS")
		)
		(fp_rect
			(start -3.556 3.81)
			(end 3.556 -3.81)
			(stroke
				(width 0)
				(type default)
			)
			(fill no)
			(layer "F.CrtYd")
		)
		(fp_poly
			(pts
				(xy -3.556 -3.81) (xy 3.556 -3.81) (xy 3.556 3.81) (xy -3.556 3.81)
			)
			(stroke
				(width 0)
				(type default)
			)
			(fill no)
			(layer "F.Fab")
		)
		(pad "1" smd rect
			(at -2.92608 2.8194 270)
			(size 0.3556 1.524)
			(layers "F.Cu" "F.Mask" "F.Paste")
			(net "Net_133")
		)
		(pad "2" smd rect
			(at -2.27584 2.8194 270)
			(size 0.3556 1.524)
			(layers "F.Cu" "F.Mask" "F.Paste")
			(net "I2C_EXP_LOC_SCL_OUT")
		)
		(pad "3" smd rect
			(at -1.6256 2.8194 270)
			(size 0.3556 1.524)
			(layers "F.Cu" "F.Mask" "F.Paste")
			(net "I2C_EXP_LOC_SDA_OUT")
		)
		(pad "4" smd rect
			(at -0.97536 2.8194 270)
			(size 0.3556 1.524)
			(layers "F.Cu" "F.Mask" "F.Paste")
			(net "I2C_EXP_RMT_SCL_OUT")
		)
		(pad "5" smd rect
			(at -0.32512 2.8194 270)
			(size 0.3556 1.524)
			(layers "F.Cu" "F.Mask" "F.Paste")
			(net "I2C_EXP_RMT_SDA_OUT")
		)
		(pad "6" smd rect
			(at 0.32512 2.8194 270)
			(size 0.3556 1.524)
			(layers "F.Cu" "F.Mask" "F.Paste")
			(net "I2C_SCC_SCL_OUT")
		)
		(pad "7" smd rect
			(at 0.97536 2.8194 270)
			(size 0.3556 1.524)
			(layers "F.Cu" "F.Mask" "F.Paste")
			(net "I2C_SCC_SDA_OUT")
		)
		(pad "8" smd rect
			(at 1.6256 2.8194 270)
			(size 0.3556 1.524)
			(layers "F.Cu" "F.Mask" "F.Paste")
			(net "I2C_DPB_SCL_OUT")
		)
		(pad "9" smd rect
			(at 2.27584 2.8194 270)
			(size 0.3556 1.524)
			(layers "F.Cu" "F.Mask" "F.Paste")
			(net "I2C_DPB_SDA_OUT")
		)
		(pad "10" smd rect
			(at 2.92608 2.8194 270)
			(size 0.3556 1.524)
			(layers "F.Cu" "F.Mask" "F.Paste")
			(net "GND")
		)
		(pad "11" smd rect
			(at 2.92608 -2.8194 270)
			(size 0.3556 1.524)
			(layers "F.Cu" "F.Mask" "F.Paste")
			(net "I2C_DPB_SDA_R")
		)
		(pad "12" smd rect
			(at 2.27584 -2.8194 270)
			(size 0.3556 1.524)
			(layers "F.Cu" "F.Mask" "F.Paste")
			(net "I2C_DPB_SCL_R")
		)
		(pad "13" smd rect
			(at 1.6256 -2.8194 270)
			(size 0.3556 1.524)
			(layers "F.Cu" "F.Mask" "F.Paste")
			(net "I2C_SCC_SDA_R")
		)
		(pad "14" smd rect
			(at 0.97536 -2.8194 270)
			(size 0.3556 1.524)
			(layers "F.Cu" "F.Mask" "F.Paste")
			(net "I2C_SCC_SCL_R")
		)
		(pad "15" smd rect
			(at 0.32512 -2.8194 270)
			(size 0.3556 1.524)
			(layers "F.Cu" "F.Mask" "F.Paste")
			(net "I2C_EXP_RMT_SDA_R")
		)
		(pad "16" smd rect
			(at -0.32512 -2.8194 270)
			(size 0.3556 1.524)
			(layers "F.Cu" "F.Mask" "F.Paste")
			(net "I2C_EXP_RMT_SCL_R")
		)
		(pad "17" smd rect
			(at -0.97536 -2.8194 270)
			(size 0.3556 1.524)
			(layers "F.Cu" "F.Mask" "F.Paste")
			(net "I2C_EXP_LOC_SDA_R")
		)
		(pad "18" smd rect
			(at -1.6256 -2.8194 270)
			(size 0.3556 1.524)
			(layers "F.Cu" "F.Mask" "F.Paste")
			(net "I2C_EXP_LOC_SCL_R")
		)
		(pad "19" smd rect
			(at -2.27584 -2.8194 270)
			(size 0.3556 1.524)
			(layers "F.Cu" "F.Mask" "F.Paste")
			(net "PWRGD_P3V3_STBY_N_R1")
		)
		(pad "20" smd rect
			(at -2.92608 -2.8194 270)
			(size 0.3556 1.524)
			(layers "F.Cu" "F.Mask" "F.Paste")
			(net "P3V3_STBY")
		)
	)
	(footprint ""
		(layer "F.Cu")
		(at 65.778126 -137.978134 180)
		(property "Reference" "R731"
			(at 0 0 180)
			(layer "F.SilkS")
			(hide yes)
			(effects
				(font
					(size 1.27 1.27)
				)
			)
		)
		(property "Value" "0R2J-2-GP"
			(at 0.064008 -3.993896 180)
			(unlocked yes)
			(layer "F.Fab")
			(hide yes)
			(effects
				(font
					(size 1.016 1.016)
					(thickness 0.1524)
				)
			)
		)
		(property "Device Type" "R402H16"
			(at 0.064008 -5.517896 180)
			(unlocked yes)
			(layer "F.Fab")
			(hide yes)
			(effects
				(font
					(size 1.016 1.016)
					(thickness 0.1524)
				)
			)
		)
		(duplicate_pad_numbers_are_jumpers no)
		(fp_line
			(start 0.508 -0.9398)
			(end -0.508 -0.9398)
			(stroke
				(width 0.1524)
				(type default)
			)
			(layer "F.SilkS")
		)
		(fp_line
			(start -0.508 -0.9398)
			(end -0.508 0.9398)
			(stroke
				(width 0.1524)
				(type default)
			)
			(layer "F.SilkS")
		)
		(fp_rect
			(start -0.508 0.9398)
			(end 0.508 -0.9398)
			(stroke
				(width 0)
				(type default)
			)
			(fill no)
			(layer "F.CrtYd")
		)
		(fp_rect
			(start -0.508 0.9398)
			(end 0.508 -0.9398)
			(stroke
				(width 0)
				(type default)
			)
			(fill no)
			(layer "F.Fab")
		)
		(pad "1" smd custom
			(at 0 -0.4445 180)
			(size 0.1397 0.1397)
			(layers "F.Cu" "F.Mask" "F.Paste")
			(net "COMP_SPARE_1")
			(options
				(clearance outline)
				(anchor circle)
			)
			(primitives
				(gr_poly
					(pts
						(arc
							(start -0.1778 -0.2794)
							(mid -0.249642 -0.249642)
							(end -0.2794 -0.1778)
						)
						(arc
							(start -0.2794 0.1778)
							(mid -0.249642 0.249642)
							(end -0.1778 0.2794)
						)
						(arc
							(start 0.1778 0.2794)
							(mid 0.249642 0.249642)
							(end 0.2794 0.1778)
						)
						(arc
							(start 0.2794 -0.1778)
							(mid 0.249642 -0.249642)
							(end 0.1778 -0.2794)
						)
					)
					(width 0)
					(fill yes)
				)
			)
		)
		(pad "2" smd custom
			(at 0 0.4445 180)
			(size 0.1397 0.1397)
			(layers "F.Cu" "F.Mask" "F.Paste")
			(net "COMP_SPARE_1_R")
			(options
				(clearance outline)
				(anchor circle)
			)
			(primitives
				(gr_poly
					(pts
						(arc
							(start -0.1778 -0.2794)
							(mid -0.249642 -0.249642)
							(end -0.2794 -0.1778)
						)
						(arc
							(start -0.2794 0.1778)
							(mid -0.249642 0.249642)
							(end -0.1778 0.2794)
						)
						(arc
							(start 0.1778 0.2794)
							(mid 0.249642 0.249642)
							(end 0.2794 0.1778)
						)
						(arc
							(start 0.2794 -0.1778)
							(mid 0.249642 -0.249642)
							(end 0.1778 -0.2794)
						)
					)
					(width 0)
					(fill yes)
				)
			)
		)
	)
	(footprint ""
		(layer "F.Cu")
		(at 112.646206 -11.201654)
		(property "Reference" "R453"
			(at 0 0 0)
			(layer "F.SilkS")
			(hide yes)
			(effects
				(font
					(size 1.27 1.27)
				)
			)
		)
		(property "Value" "100KR2J-4-GP"
			(at 0.064008 -3.993896 0)
			(unlocked yes)
			(layer "F.Fab")
			(hide yes)
			(effects
				(font
					(size 1.016 1.016)
					(thickness 0.1524)
				)
			)
		)
		(property "Device Type" "R402H15"
			(at 0.064008 -5.517896 0)
			(unlocked yes)
			(layer "F.Fab")
			(hide yes)
			(effects
				(font
					(size 1.016 1.016)
					(thickness 0.1524)
				)
			)
		)
		(duplicate_pad_numbers_are_jumpers no)
		(fp_line
			(start -0.508 -0.9398)
			(end -0.508 0.9398)
			(stroke
				(width 0.1524)
				(type default)
			)
			(layer "F.SilkS")
		)
		(fp_line
			(start 0.508 -0.9398)
			(end -0.508 -0.9398)
			(stroke
				(width 0.1524)
				(type default)
			)
			(layer "F.SilkS")
		)
		(fp_rect
			(start -0.508 0.9398)
			(end 0.508 -0.9398)
			(stroke
				(width 0)
				(type default)
			)
			(fill no)
			(layer "F.CrtYd")
		)
		(fp_rect
			(start -0.508 0.9398)
			(end 0.508 -0.9398)
			(stroke
				(width 0)
				(type default)
			)
			(fill no)
			(layer "F.Fab")
		)
		(pad "1" smd custom
			(at 0 -0.4445)
			(size 0.1397 0.1397)
			(layers "F.Cu" "F.Mask" "F.Paste")
			(net "MB0_VCAP_R")
			(options
				(clearance outline)
				(anchor circle)
			)
			(primitives
				(gr_poly
					(pts
						(arc
							(start -0.1778 -0.2794)
							(mid -0.249642 -0.249642)
							(end -0.2794 -0.1778)
						)
						(arc
							(start -0.2794 0.1778)
							(mid -0.249642 0.249642)
							(end -0.1778 0.2794)
						)
						(arc
							(start 0.1778 0.2794)
							(mid 0.249642 0.249642)
							(end 0.2794 0.1778)
						)
						(arc
							(start 0.2794 -0.1778)
							(mid 0.249642 -0.249642)
							(end 0.1778 -0.2794)
						)
					)
					(width 0)
					(fill yes)
				)
			)
		)
		(pad "2" smd custom
			(at 0 0.4445)
			(size 0.1397 0.1397)
			(layers "F.Cu" "F.Mask" "F.Paste")
			(net "MB0_ISET_R")
			(options
				(clearance outline)
				(anchor circle)
			)
			(primitives
				(gr_poly
					(pts
						(arc
							(start -0.1778 -0.2794)
							(mid -0.249642 -0.249642)
							(end -0.2794 -0.1778)
						)
						(arc
							(start -0.2794 0.1778)
							(mid -0.249642 0.249642)
							(end -0.1778 0.2794)
						)
						(arc
							(start 0.1778 0.2794)
							(mid 0.249642 0.249642)
							(end 0.2794 0.1778)
						)
						(arc
							(start 0.2794 -0.1778)
							(mid 0.249642 -0.249642)
							(end 0.1778 -0.2794)
						)
					)
					(width 0)
					(fill yes)
				)
			)
		)
	)
	(footprint ""
		(layer "F.Cu")
		(at 61.681868 -145.43659 -90)
		(property "Reference" "R162"
			(at 0 0 270)
			(layer "F.SilkS")
			(hide yes)
			(effects
				(font
					(size 1.27 1.27)
				)
			)
		)
		(property "Value" "0R2J-2-GP"
			(at 0.064008 -3.993896 270)
			(unlocked yes)
			(layer "F.Fab")
			(hide yes)
			(effects
				(font
					(size 1.016 1.016)
					(thickness 0.1524)
				)
			)
		)
		(property "Device Type" "R402H16"
			(at 0.064008 -5.517896 270)
			(unlocked yes)
			(layer "F.Fab")
			(hide yes)
			(effects
				(font
					(size 1.016 1.016)
					(thickness 0.1524)
				)
			)
		)
		(duplicate_pad_numbers_are_jumpers no)
		(fp_line
			(start -0.508 -0.9398)
			(end -0.508 0.9398)
			(stroke
				(width 0.1524)
				(type default)
			)
			(layer "F.SilkS")
		)
		(fp_line
			(start 0.508 -0.9398)
			(end -0.508 -0.9398)
			(stroke
				(width 0.1524)
				(type default)
			)
			(layer "F.SilkS")
		)
		(fp_rect
			(start -0.508 0.9398)
			(end 0.508 -0.9398)
			(stroke
				(width 0)
				(type default)
			)
			(fill no)
			(layer "F.CrtYd")
		)
		(fp_rect
			(start -0.508 0.9398)
			(end 0.508 -0.9398)
			(stroke
				(width 0)
				(type default)
			)
			(fill no)
			(layer "F.Fab")
		)
		(pad "1" smd custom
			(at 0 -0.4445 270)
			(size 0.1397 0.1397)
			(layers "F.Cu" "F.Mask" "F.Paste")
			(net "I2C_SCC_SDA_OUT")
			(options
				(clearance outline)
				(anchor circle)
			)
			(primitives
				(gr_poly
					(pts
						(arc
							(start -0.1778 -0.2794)
							(mid -0.249642 -0.249642)
							(end -0.2794 -0.1778)
						)
						(arc
							(start -0.2794 0.1778)
							(mid -0.249642 0.249642)
							(end -0.1778 0.2794)
						)
						(arc
							(start 0.1778 0.2794)
							(mid 0.249642 0.249642)
							(end 0.2794 0.1778)
						)
						(arc
							(start 0.2794 -0.1778)
							(mid 0.249642 -0.249642)
							(end 0.1778 -0.2794)
						)
					)
					(width 0)
					(fill yes)
				)
			)
		)
		(pad "2" smd custom
			(at 0 0.4445 270)
			(size 0.1397 0.1397)
			(layers "F.Cu" "F.Mask" "F.Paste")
			(net "BMC_SMB3_DAT")
			(options
				(clearance outline)
				(anchor circle)
			)
			(primitives
				(gr_poly
					(pts
						(arc
							(start -0.1778 -0.2794)
							(mid -0.249642 -0.249642)
							(end -0.2794 -0.1778)
						)
						(arc
							(start -0.2794 0.1778)
							(mid -0.249642 0.249642)
							(end -0.1778 0.2794)
						)
						(arc
							(start 0.1778 0.2794)
							(mid 0.249642 0.249642)
							(end 0.2794 0.1778)
						)
						(arc
							(start 0.2794 -0.1778)
							(mid 0.249642 -0.249642)
							(end 0.1778 -0.2794)
						)
					)
					(width 0)
					(fill yes)
				)
			)
		)
	)
	(footprint ""
		(layer "F.Cu")
		(at 23.777956 -128.105408 180)
		(property "Reference" "LED6"
			(at 0 0 180)
			(layer "F.SilkS")
			(hide yes)
			(effects
				(font
					(size 1.27 1.27)
				)
			)
		)
		(property "Value" "LED-YG-51-GP"
			(at -2.6924 -1.4224 180)
			(unlocked yes)
			(layer "F.Fab")
			(hide yes)
			(effects
				(font
					(size 1.016 1.016)
					(thickness 0.1524)
				)
			)
		)
		(property "Device Type" "LED1608AKH40"
			(at -2.6924 -2.9464 180)
			(unlocked yes)
			(layer "F.Fab")
			(hide yes)
			(effects
				(font
					(size 1.016 1.016)
					(thickness 0.1524)
				)
			)
		)
		(duplicate_pad_numbers_are_jumpers no)
		(fp_line
			(start 0.7493 1.651)
			(end 0.7493 1.1811)
			(stroke
				(width 0.3302)
				(type default)
			)
			(layer "F.SilkS")
		)
		(fp_line
			(start 0.6604 1.3716)
			(end -0.6604 1.3716)
			(stroke
				(width 0.1524)
				(type default)
			)
			(layer "F.SilkS")
		)
		(fp_line
			(start 0.6604 -1.3716)
			(end 0.6604 1.3716)
			(stroke
				(width 0.1524)
				(type default)
			)
			(layer "F.SilkS")
		)
		(fp_line
			(start -0.5969 1.5494)
			(end 0.5842 1.5494)
			(stroke
				(width 0.508)
				(type default)
			)
			(layer "F.SilkS")
		)
		(fp_line
			(start -0.6604 1.3716)
			(end -0.6604 -1.3716)
			(stroke
				(width 0.1524)
				(type default)
			)
			(layer "F.SilkS")
		)
		(fp_line
			(start -0.6604 -1.3716)
			(end 0.6604 -1.3716)
			(stroke
				(width 0.1524)
				(type default)
			)
			(layer "F.SilkS")
		)
		(fp_line
			(start -0.7493 1.651)
			(end -0.7493 1.1811)
			(stroke
				(width 0.3302)
				(type default)
			)
			(layer "F.SilkS")
		)
		(fp_rect
			(start -0.6223 1.3335)
			(end 0.6223 -1.3335)
			(stroke
				(width 0)
				(type default)
			)
			(fill no)
			(layer "F.CrtYd")
		)
		(fp_rect
			(start -0.6223 1.3335)
			(end 0.6223 -1.3335)
			(stroke
				(width 0)
				(type default)
			)
			(fill no)
			(layer "F.Fab")
		)
		(pad "A" smd custom
			(at 0 -0.762 180)
			(size 0.2159 0.2159)
			(layers "F.Cu" "F.Mask" "F.Paste")
			(net "BMC_HBLED_R")
			(options
				(clearance outline)
				(anchor circle)
			)
			(primitives
				(gr_poly
					(pts
						(arc
							(start -0.3302 -0.4318)
							(mid -0.402042 -0.402042)
							(end -0.4318 -0.3302)
						)
						(arc
							(start -0.4318 0.3302)
							(mid -0.402042 0.402042)
							(end -0.3302 0.4318)
						)
						(arc
							(start 0.3302 0.4318)
							(mid 0.402042 0.402042)
							(end 0.4318 0.3302)
						)
						(arc
							(start 0.4318 -0.3302)
							(mid 0.402042 -0.402042)
							(end 0.3302 -0.4318)
						)
					)
					(width 0)
					(fill yes)
				)
			)
		)
		(pad "K" smd custom
			(at 0 0.762 180)
			(size 0.2159 0.2159)
			(layers "F.Cu" "F.Mask" "F.Paste")
			(net "BMC_HBLED")
			(options
				(clearance outline)
				(anchor circle)
			)
			(primitives
				(gr_poly
					(pts
						(arc
							(start -0.3302 -0.4318)
							(mid -0.402042 -0.402042)
							(end -0.4318 -0.3302)
						)
						(arc
							(start -0.4318 0.3302)
							(mid -0.402042 0.402042)
							(end -0.3302 0.4318)
						)
						(arc
							(start 0.3302 0.4318)
							(mid 0.402042 0.402042)
							(end 0.4318 0.3302)
						)
						(arc
							(start 0.4318 -0.3302)
							(mid 0.402042 -0.402042)
							(end 0.3302 -0.4318)
						)
					)
					(width 0)
					(fill yes)
				)
			)
		)
	)
)
